(kicad_pcb
	(version 20241229)
	(generator "pcbnew")
	(generator_version "9.0")
	(general
		(thickness 1.294)
		(legacy_teardrops no)
	)
	(paper "A3")
	(title_block
		(title "Kintex 410T devboard")
		(date "2024-04-03")
		(rev "1.1.2")
		(comment 9 "footprints 951-956 of 975")
	)
	(layers
		(0 "F.Cu" mixed)
		(4 "In1.Cu" power)
		(6 "In2.Cu" power)
		(8 "In3.Cu" mixed)
		(10 "In4.Cu" power)
		(12 "In5.Cu" mixed)
		(14 "In6.Cu" power)
		(16 "In7.Cu" mixed)
		(18 "In8.Cu" power)
		(2 "B.Cu" mixed)
		(9 "F.Adhes" user "F.Adhesive")
		(11 "B.Adhes" user "B.Adhesive")
		(13 "F.Paste" user)
		(15 "B.Paste" user)
		(5 "F.SilkS" user "F.Silkscreen")
		(7 "B.SilkS" user "B.Silkscreen")
		(1 "F.Mask" user)
		(3 "B.Mask" user)
		(17 "Dwgs.User" user "User.Drawings")
		(19 "Cmts.User" user "User.Comments")
		(21 "Eco1.User" user "User.Eco1")
		(23 "Eco2.User" user "User.Eco2")
		(25 "Edge.Cuts" user)
		(27 "Margin" user)
		(31 "F.CrtYd" user "F.Courtyard")
		(29 "B.CrtYd" user "B.Courtyard")
		(35 "F.Fab" user)
		(33 "B.Fab" user)
	)
	(footprint "antmicro-footprints:C_0402_1005Metric"
		(layer "B.Cu")
		(at 212 126.52 180)
		(descr "Capacitor SMD 0402")
		(tags "capacitor SMD 0402")
		(property "Reference" "C26"
			(at -1.075 0.45 0)
			(layer "B.SilkS")
			(effects
				(font
					(size 0.7 0.7)
					(thickness 0.15)
				)
				(justify left bottom mirror)
			)
		)
		(property "Value" "C_100n_0402"
			(at 0 -1.169 0)
			(layer "B.Fab")
			(effects
				(font
					(size 0.7 0.7)
					(thickness 0.15)
				)
				(justify left bottom mirror)
			)
		)
		(property "Description" "SMD Multilayer Ceramic Capacitor, 0.1 µF, 50 V, 0402 [1005 Metric], ± 10%, X5R, GRM Series"
			(at 0 0 180)
			(layer "F.Fab")
			(hide yes)
			(effects
				(font
					(size 1.27 1.27)
					(thickness 0.15)
				)
			)
		)
		(property "Author" "Antmicro"
			(at 424 253.04 0)
			(layer "B.Fab")
			(hide yes)
			(effects
				(font
					(size 1 1)
					(thickness 0.15)
				)
				(justify mirror)
			)
		)
		(property "Dielectric" "X5R"
			(at 424 253.04 0)
			(layer "B.Fab")
			(hide yes)
			(effects
				(font
					(size 1 1)
					(thickness 0.15)
				)
				(justify mirror)
			)
		)
		(property "License" "Apache-2.0"
			(at 424 253.04 0)
			(layer "B.Fab")
			(hide yes)
			(effects
				(font
					(size 1 1)
					(thickness 0.15)
				)
				(justify mirror)
			)
		)
		(property "MPN" "GRM155R61H104KE14D"
			(at 424 253.04 0)
			(layer "B.Fab")
			(hide yes)
			(effects
				(font
					(size 1 1)
					(thickness 0.15)
				)
				(justify mirror)
			)
		)
		(property "Manufacturer" "Murata"
			(at 424 253.04 0)
			(layer "B.Fab")
			(hide yes)
			(effects
				(font
					(size 1 1)
					(thickness 0.15)
				)
				(justify mirror)
			)
		)
		(property "Val" "100n"
			(at 424 253.04 0)
			(layer "B.Fab")
			(hide yes)
			(effects
				(font
					(size 1 1)
					(thickness 0.15)
				)
				(justify mirror)
			)
		)
		(property "Voltage" "50V"
			(at 424 253.04 0)
			(layer "B.Fab")
			(hide yes)
			(effects
				(font
					(size 1 1)
					(thickness 0.15)
				)
				(justify mirror)
			)
		)
		(sheetname "FPGA Bank 14 & 15")
		(sheetfile "fpga-bank-14-15.kicad_sch")
		(attr smd)
		(fp_rect
			(start -0.925 0.47)
			(end 0.925 -0.47)
			(stroke
				(width 0.05)
				(type default)
			)
			(fill no)
			(layer "B.CrtYd")
		)
		(fp_line
			(start 0.504 0.25)
			(end 0.504 -0.248)
			(stroke
				(width 0.15)
				(type solid)
			)
			(layer "B.Fab")
		)
		(fp_line
			(start 0.504 -0.248)
			(end -0.494 -0.248)
			(stroke
				(width 0.15)
				(type solid)
			)
			(layer "B.Fab")
		)
		(fp_line
			(start -0.494 0.25)
			(end 0.504 0.25)
			(stroke
				(width 0.15)
				(type solid)
			)
			(layer "B.Fab")
		)
		(fp_line
			(start -0.494 -0.248)
			(end -0.494 0.25)
			(stroke
				(width 0.15)
				(type solid)
			)
			(layer "B.Fab")
		)
		(pad "1" smd roundrect
			(at -0.48 0 180)
			(size 0.59 0.64)
			(layers "B.Cu" "B.Mask" "B.Paste")
			(roundrect_rratio 0.25)
			(net 1 "GND")
			(pintype "passive")
		)
		(pad "2" smd roundrect
			(at 0.48 0 180)
			(size 0.59 0.64)
			(layers "B.Cu" "B.Mask" "B.Paste")
			(roundrect_rratio 0.25)
			(net 2 "VCC_USR_A")
			(pintype "passive")
		)
	)
	(footprint "antmicro-footprints:R_0402_1005Metric"
		(layer "B.Cu")
		(at 266.001 127.7 180)
		(descr "Resistor SMD 0402")
		(tags "resistor SMD 0402")
		(property "Reference" "R170"
			(at 0.901 -0.7 0)
			(layer "B.SilkS")
			(effects
				(font
					(size 0.7 0.7)
					(thickness 0.15)
				)
				(justify left bottom mirror)
			)
		)
		(property "Value" "R_15k_0402"
			(at 0 -1.4 0)
			(layer "B.Fab")
			(effects
				(font
					(size 0.7 0.7)
					(thickness 0.15)
				)
				(justify left bottom mirror)
			)
		)
		(property "Description" "SMD Chip Resistor, 15 kohm, ± 1%, 62.5 mW, 0402 [1005 Metric], Thick Film, General Purpose"
			(at 0 0 180)
			(layer "F.Fab")
			(hide yes)
			(effects
				(font
					(size 1.27 1.27)
					(thickness 0.15)
				)
			)
		)
		(property "Author" "Antmicro"
			(at 532.002 255.4 0)
			(layer "B.Fab")
			(hide yes)
			(effects
				(font
					(size 1 1)
					(thickness 0.15)
				)
				(justify mirror)
			)
		)
		(property "DNP" "DNP"
			(at 532.002 255.4 0)
			(layer "B.Fab")
			(hide yes)
			(effects
				(font
					(size 1 1)
					(thickness 0.15)
				)
				(justify mirror)
			)
		)
		(property "License" "Apache-2.0"
			(at 532.002 255.4 0)
			(layer "B.Fab")
			(hide yes)
			(effects
				(font
					(size 1 1)
					(thickness 0.15)
				)
				(justify mirror)
			)
		)
		(property "MPN" "CR0402-FX-1502GLF"
			(at 532.002 255.4 0)
			(layer "B.Fab")
			(hide yes)
			(effects
				(font
					(size 1 1)
					(thickness 0.15)
				)
				(justify mirror)
			)
		)
		(property "Manufacturer" "Bourns"
			(at 532.002 255.4 0)
			(layer "B.Fab")
			(hide yes)
			(effects
				(font
					(size 1 1)
					(thickness 0.15)
				)
				(justify mirror)
			)
		)
		(property "Tolerance" "1%"
			(at 532.002 255.4 0)
			(layer "B.Fab")
			(hide yes)
			(effects
				(font
					(size 1 1)
					(thickness 0.15)
				)
				(justify mirror)
			)
		)
		(property "Val" "15k"
			(at 532.002 255.4 0)
			(layer "B.Fab")
			(hide yes)
			(effects
				(font
					(size 1 1)
					(thickness 0.15)
				)
				(justify mirror)
			)
		)
		(property "dnp" ""
			(at 532.002 255.4 0)
			(layer "B.Fab")
			(hide yes)
			(effects
				(font
					(size 1 1)
					(thickness 0.15)
				)
				(justify mirror)
			)
		)
		(property "exclude_from_bom" ""
			(at 532.002 255.4 0)
			(layer "B.Fab")
			(hide yes)
			(effects
				(font
					(size 1 1)
					(thickness 0.15)
				)
				(justify mirror)
			)
		)
		(sheetname "USB PHY")
		(sheetfile "usb-phy.kicad_sch")
		(attr smd exclude_from_bom)
		(fp_rect
			(start -0.925 0.47)
			(end 0.925 -0.47)
			(stroke
				(width 0.05)
				(type default)
			)
			(fill no)
			(layer "B.CrtYd")
		)
		(fp_rect
			(start -0.5 0.25)
			(end 0.5 -0.25)
			(stroke
				(width 0.15)
				(type solid)
			)
			(fill no)
			(layer "B.Fab")
		)
		(pad "1" smd roundrect
			(at -0.48 0 180)
			(size 0.59 0.64)
			(layers "B.Cu" "B.Mask" "B.Paste")
			(roundrect_rratio 0.25)
			(net 1 "GND")
			(pintype "passive")
		)
		(pad "2" smd roundrect
			(at 0.48 0 180)
			(size 0.59 0.64)
			(layers "B.Cu" "B.Mask" "B.Paste")
			(roundrect_rratio 0.25)
			(net 843 "/USB PHY/USB_USR_CONN_D-")
			(pintype "passive")
		)
	)
	(footprint "antmicro-footprints:C_0402_1005Metric"
		(layer "B.Cu")
		(at 193.25 130.75 90)
		(descr "Capacitor SMD 0402")
		(tags "capacitor SMD 0402")
		(property "Reference" "C16"
			(at 29.55 23 270)
			(layer "B.SilkS")
			(effects
				(font
					(size 0.7 0.7)
					(thickness 0.15)
				)
				(justify left bottom mirror)
			)
		)
		(property "Value" "C_100n_0402"
			(at 0 -1.169 270)
			(layer "B.Fab")
			(effects
				(font
					(size 0.7 0.7)
					(thickness 0.15)
				)
				(justify left bottom mirror)
			)
		)
		(property "Description" "SMD Multilayer Ceramic Capacitor, 0.1 µF, 50 V, 0402 [1005 Metric], ± 10%, X5R, GRM Series"
			(at 0 0 90)
			(layer "F.Fab")
			(hide yes)
			(effects
				(font
					(size 1.27 1.27)
					(thickness 0.15)
				)
			)
		)
		(property "Author" "Antmicro"
			(at 324 -62.5 0)
			(layer "B.Fab")
			(hide yes)
			(effects
				(font
					(size 1 1)
					(thickness 0.15)
				)
				(justify mirror)
			)
		)
		(property "Dielectric" "X5R"
			(at 324 -62.5 0)
			(layer "B.Fab")
			(hide yes)
			(effects
				(font
					(size 1 1)
					(thickness 0.15)
				)
				(justify mirror)
			)
		)
		(property "License" "Apache-2.0"
			(at 324 -62.5 0)
			(layer "B.Fab")
			(hide yes)
			(effects
				(font
					(size 1 1)
					(thickness 0.15)
				)
				(justify mirror)
			)
		)
		(property "MPN" "GRM155R61H104KE14D"
			(at 324 -62.5 0)
			(layer "B.Fab")
			(hide yes)
			(effects
				(font
					(size 1 1)
					(thickness 0.15)
				)
				(justify mirror)
			)
		)
		(property "Manufacturer" "Murata"
			(at 324 -62.5 0)
			(layer "B.Fab")
			(hide yes)
			(effects
				(font
					(size 1 1)
					(thickness 0.15)
				)
				(justify mirror)
			)
		)
		(property "Val" "100n"
			(at 324 -62.5 0)
			(layer "B.Fab")
			(hide yes)
			(effects
				(font
					(size 1 1)
					(thickness 0.15)
				)
				(justify mirror)
			)
		)
		(property "Voltage" "50V"
			(at 324 -62.5 0)
			(layer "B.Fab")
			(hide yes)
			(effects
				(font
					(size 1 1)
					(thickness 0.15)
				)
				(justify mirror)
			)
		)
		(sheetname "FPGA Config")
		(sheetfile "fpga-config.kicad_sch")
		(attr smd)
		(fp_rect
			(start -0.925 0.47)
			(end 0.925 -0.47)
			(stroke
				(width 0.05)
				(type default)
			)
			(fill no)
			(layer "B.CrtYd")
		)
		(fp_line
			(start 0.504 -0.248)
			(end -0.494 -0.248)
			(stroke
				(width 0.15)
				(type solid)
			)
			(layer "B.Fab")
		)
		(fp_line
			(start -0.494 -0.248)
			(end -0.494 0.25)
			(stroke
				(width 0.15)
				(type solid)
			)
			(layer "B.Fab")
		)
		(fp_line
			(start 0.504 0.25)
			(end 0.504 -0.248)
			(stroke
				(width 0.15)
				(type solid)
			)
			(layer "B.Fab")
		)
		(fp_line
			(start -0.494 0.25)
			(end 0.504 0.25)
			(stroke
				(width 0.15)
				(type solid)
			)
			(layer "B.Fab")
		)
		(pad "1" smd roundrect
			(at -0.48 0 90)
			(size 0.59 0.64)
			(layers "B.Cu" "B.Mask" "B.Paste")
			(roundrect_rratio 0.25)
			(net 1 "GND")
			(pintype "passive")
		)
		(pad "2" smd roundrect
			(at 0.48 0 90)
			(size 0.59 0.64)
			(layers "B.Cu" "B.Mask" "B.Paste")
			(roundrect_rratio 0.25)
			(net 24 "+3V3")
			(pintype "passive")
		)
	)
	(footprint "antmicro-footprints:C_0402_1005Metric"
		(layer "B.Cu")
		(at 268.001 127.7)
		(descr "Capacitor SMD 0402")
		(tags "capacitor SMD 0402")
		(property "Reference" "C393"
			(at -1.201 1.275 0)
			(layer "B.SilkS")
			(effects
				(font
					(size 0.7 0.7)
					(thickness 0.15)
				)
				(justify right bottom mirror)
			)
		)
		(property "Value" "C_100n_0402"
			(at 0 -1.4 0)
			(layer "B.Fab")
			(effects
				(font
					(size 0.7 0.7)
					(thickness 0.15)
				)
				(justify right bottom mirror)
			)
		)
		(property "Description" "SMD Multilayer Ceramic Capacitor, 0.1 µF, 50 V, 0402 [1005 Metric], ± 10%, X5R, GRM Series"
			(at 0 0 0)
			(layer "F.Fab")
			(hide yes)
			(effects
				(font
					(size 1.27 1.27)
					(thickness 0.15)
				)
			)
		)
		(property "Author" "Antmicro"
			(at 0 0 0)
			(layer "B.Fab")
			(hide yes)
			(effects
				(font
					(size 1 1)
					(thickness 0.15)
				)
				(justify mirror)
			)
		)
		(property "Dielectric" "X5R"
			(at 0 0 0)
			(layer "B.Fab")
			(hide yes)
			(effects
				(font
					(size 1 1)
					(thickness 0.15)
				)
				(justify mirror)
			)
		)
		(property "License" "Apache-2.0"
			(at 0 0 0)
			(layer "B.Fab")
			(hide yes)
			(effects
				(font
					(size 1 1)
					(thickness 0.15)
				)
				(justify mirror)
			)
		)
		(property "MPN" "GRM155R61H104KE14D"
			(at 0 0 0)
			(layer "B.Fab")
			(hide yes)
			(effects
				(font
					(size 1 1)
					(thickness 0.15)
				)
				(justify mirror)
			)
		)
		(property "Manufacturer" "Murata"
			(at 0 0 0)
			(layer "B.Fab")
			(hide yes)
			(effects
				(font
					(size 1 1)
					(thickness 0.15)
				)
				(justify mirror)
			)
		)
		(property "Val" "100n"
			(at 0 0 0)
			(layer "B.Fab")
			(hide yes)
			(effects
				(font
					(size 1 1)
					(thickness 0.15)
				)
				(justify mirror)
			)
		)
		(property "Voltage" "50V"
			(at 0 0 0)
			(layer "B.Fab")
			(hide yes)
			(effects
				(font
					(size 1 1)
					(thickness 0.15)
				)
				(justify mirror)
			)
		)
		(sheetname "SPI Flash + SD Card")
		(sheetfile "spi-flash.kicad_sch")
		(attr smd)
		(fp_rect
			(start -0.925 0.47)
			(end 0.925 -0.47)
			(stroke
				(width 0.05)
				(type default)
			)
			(fill no)
			(layer "B.CrtYd")
		)
		(fp_line
			(start -0.494 -0.248)
			(end -0.494 0.25)
			(stroke
				(width 0.15)
				(type solid)
			)
			(layer "B.Fab")
		)
		(fp_line
			(start -0.494 0.25)
			(end 0.504 0.25)
			(stroke
				(width 0.15)
				(type solid)
			)
			(layer "B.Fab")
		)
		(fp_line
			(start 0.504 -0.248)
			(end -0.494 -0.248)
			(stroke
				(width 0.15)
				(type solid)
			)
			(layer "B.Fab")
		)
		(fp_line
			(start 0.504 0.25)
			(end 0.504 -0.248)
			(stroke
				(width 0.15)
				(type solid)
			)
			(layer "B.Fab")
		)
		(pad "1" smd roundrect
			(at -0.48 0)
			(size 0.59 0.64)
			(layers "B.Cu" "B.Mask" "B.Paste")
			(roundrect_rratio 0.25)
			(net 1 "GND")
			(pintype "passive")
		)
		(pad "2" smd roundrect
			(at 0.48 0)
			(size 0.59 0.64)
			(layers "B.Cu" "B.Mask" "B.Paste")
			(roundrect_rratio 0.25)
			(net 16 "Net-(J23-SHIELD)")
			(pintype "passive")
		)
	)
	(footprint "antmicro-footprints:R_0402_1005Metric"
		(layer "B.Cu")
		(at 242.501 134.9)
		(descr "Resistor SMD 0402")
		(tags "resistor SMD 0402")
		(property "Reference" "R162"
			(at -0.751 0.4 180)
			(layer "B.SilkS")
			(effects
				(font
					(size 0.7 0.7)
					(thickness 0.15)
				)
				(justify left bottom mirror)
			)
		)
		(property "Value" "R_33R_0402"
			(at 0 -1.4 180)
			(layer "B.Fab")
			(effects
				(font
					(size 0.7 0.7)
					(thickness 0.15)
				)
				(justify left bottom mirror)
			)
		)
		(property "Description" "SMD Chip Resistor, 33 ohm, ± 1%, 62.5 mW, 0402 [1005 Metric], Thick Film, General Purpose"
			(at 0 0 0)
			(layer "F.Fab")
			(hide yes)
			(effects
				(font
					(size 1.27 1.27)
					(thickness 0.15)
				)
			)
		)
		(property "Author" "Antmicro"
			(at 0 0 0)
			(layer "B.Fab")
			(hide yes)
			(effects
				(font
					(size 1 1)
					(thickness 0.15)
				)
				(justify mirror)
			)
		)
		(property "License" "Apache-2.0"
			(at 0 0 0)
			(layer "B.Fab")
			(hide yes)
			(effects
				(font
					(size 1 1)
					(thickness 0.15)
				)
				(justify mirror)
			)
		)
		(property "MPN" "CR0402-FX-33R0GLF"
			(at 0 0 0)
			(layer "B.Fab")
			(hide yes)
			(effects
				(font
					(size 1 1)
					(thickness 0.15)
				)
				(justify mirror)
			)
		)
		(property "Manufacturer" "Bourns"
			(at 0 0 0)
			(layer "B.Fab")
			(hide yes)
			(effects
				(font
					(size 1 1)
					(thickness 0.15)
				)
				(justify mirror)
			)
		)
		(property "Tolerance" "1%"
			(at 0 0 0)
			(layer "B.Fab")
			(hide yes)
			(effects
				(font
					(size 1 1)
					(thickness 0.15)
				)
				(justify mirror)
			)
		)
		(property "Val" "33R"
			(at 0 0 0)
			(layer "B.Fab")
			(hide yes)
			(effects
				(font
					(size 1 1)
					(thickness 0.15)
				)
				(justify mirror)
			)
		)
		(sheetname "USB PHY")
		(sheetfile "usb-phy.kicad_sch")
		(attr smd)
		(fp_rect
			(start -0.925 0.47)
			(end 0.925 -0.47)
			(stroke
				(width 0.05)
				(type default)
			)
			(fill no)
			(layer "B.CrtYd")
		)
		(fp_rect
			(start -0.5 0.25)
			(end 0.5 -0.25)
			(stroke
				(width 0.15)
				(type solid)
			)
			(fill no)
			(layer "B.Fab")
		)
		(pad "1" smd roundrect
			(at -0.48 0)
			(size 0.59 0.64)
			(layers "B.Cu" "B.Mask" "B.Paste")
			(roundrect_rratio 0.25)
			(net 922 "/USB PHY/FTDI_UART0_RX")
			(pintype "passive")
		)
		(pad "2" smd roundrect
			(at 0.48 0)
			(size 0.59 0.64)
			(layers "B.Cu" "B.Mask" "B.Paste")
			(roundrect_rratio 0.25)
			(net 55 "/FPGA Bank 12 & 13/UART0.TX")
			(pintype "passive")
		)
	)
	(footprint "antmicro-footprints:R_0402_1005Metric"
		(layer "B.Cu")
		(at 240.199999 84.699999 -90)
		(descr "Resistor SMD 0402")
		(tags "resistor SMD 0402")
		(property "Reference" "R117"
			(at 0.750001 -0.425001 90)
			(layer "B.SilkS")
			(effects
				(font
					(size 0.7 0.7)
					(thickness 0.15)
				)
				(justify left bottom mirror)
			)
		)
		(property "Value" "R_100R_0402"
			(at 0 -1.4 90)
			(layer "B.Fab")
			(effects
				(font
					(size 0.7 0.7)
					(thickness 0.15)
				)
				(justify left bottom mirror)
			)
		)
		(property "Description" "SMD Chip Resistor, 100 ohm, ± 1%, 62.5 mW, 0402 [1005 Metric], Thick Film, General Purpose"
			(at 0 0 270)
			(layer "F.Fab")
			(hide yes)
			(effects
				(font
					(size 1.27 1.27)
					(thickness 0.15)
				)
			)
		)
		(property "Author" "Antmicro"
			(at 155.5 324.899998 0)
			(layer "B.Fab")
			(hide yes)
			(effects
				(font
					(size 1 1)
					(thickness 0.15)
				)
				(justify mirror)
			)
		)
		(property "License" "Apache-2.0"
			(at 155.5 324.899998 0)
			(layer "B.Fab")
			(hide yes)
			(effects
				(font
					(size 1 1)
					(thickness 0.15)
				)
				(justify mirror)
			)
		)
		(property "MPN" "CR0402-FX-1000GLF"
			(at 155.5 324.899998 0)
			(layer "B.Fab")
			(hide yes)
			(effects
				(font
					(size 1 1)
					(thickness 0.15)
				)
				(justify mirror)
			)
		)
		(property "Manufacturer" "Bourns"
			(at 155.5 324.899998 0)
			(layer "B.Fab")
			(hide yes)
			(effects
				(font
					(size 1 1)
					(thickness 0.15)
				)
				(justify mirror)
			)
		)
		(property "Tolerance" "1%"
			(at 155.5 324.899998 0)
			(layer "B.Fab")
			(hide yes)
			(effects
				(font
					(size 1 1)
					(thickness 0.15)
				)
				(justify mirror)
			)
		)
		(property "Val" "100R"
			(at 155.5 324.899998 0)
			(layer "B.Fab")
			(hide yes)
			(effects
				(font
					(size 1 1)
					(thickness 0.15)
				)
				(justify mirror)
			)
		)
		(sheetname "User GPIO + LED + button + DIP switch")
		(sheetfile "user-gpio.kicad_sch")
		(attr smd)
		(fp_rect
			(start -0.925 0.47)
			(end 0.925 -0.47)
			(stroke
				(width 0.05)
				(type default)
			)
			(fill no)
			(layer "B.CrtYd")
		)
		(fp_rect
			(start -0.5 0.25)
			(end 0.5 -0.25)
			(stroke
				(width 0.15)
				(type solid)
			)
			(fill no)
			(layer "B.Fab")
		)
		(pad "1" smd roundrect
			(at -0.48 0 270)
			(size 0.59 0.64)
			(layers "B.Cu" "B.Mask" "B.Paste")
			(roundrect_rratio 0.25)
			(net 814 "/User GPIO + LED + button + DIP switch/PMOD_B_8")
			(pintype "passive")
		)
		(pad "2" smd roundrect
			(at 0.48 0 270)
			(size 0.59 0.64)
			(layers "B.Cu" "B.Mask" "B.Paste")
			(roundrect_rratio 0.25)
			(net 451 "/FPGA Bank 12 & 13/PMOD_B.IO8")
			(pintype "passive")
		)
	)
)
